# BASEBOARD_FAB2 (Tioga Pass) — schematic netlist excerpt (pin names and nets, part order shuffled) for the footprints in the layout excerpt that follows; sources: Cadence DE-HDL packaged netlist, KiCad conversion of Wiwynn_Tioga_Pass_MB.brd

RF18  RES  1.0K 0.1% CHIP  pkg 0402  page 218 : A = VR_PVDDQ_DEF_AIREF2 ; B = ISENSE_PVDDQ_DEF_PH2_IMON
CT24  CAP_A  0.1UF 16V 10% X7R  pkg 0402V  page 207 : A = VR_PVCCIN_CPU1_AIREF1 ; B = GND
C833  CAP  0.22UF 16V 10% X7R  pkg 0402  page 244 : A = P3E_CPU0_PE1_PCH_TXP<11> ; B = P3E_CPU0_PE1_PCH_CON_TXP<11>

(kicad_pcb
	(version 20260206)
	(generator "pcbnew")
	(generator_version "10.0")
	(general
		(thickness 1.6)
		(legacy_teardrops no)
	)
	(paper "A4")
	(title_block
		(title "Wiwynn_Tioga_Pass_MB.brd")
		(comment 1 "Tioga Pass / footprints 1828-1830 of 4770")
	)
	(layers
		(0 "F.Cu" signal "TOP")
		(4 "In1.Cu" signal "L2GND")
		(6 "In2.Cu" signal "L3")
		(8 "In3.Cu" signal "L4GND")
		(10 "In4.Cu" signal "L5")
		(12 "In5.Cu" signal "L6GND")
		(14 "In6.Cu" signal "L7VCC")
		(16 "In7.Cu" signal "L8VCC")
		(18 "In8.Cu" signal "L9GND")
		(20 "In9.Cu" signal "L10")
		(22 "In10.Cu" signal "L11GND")
		(24 "In11.Cu" signal "L12")
		(26 "In12.Cu" signal "L13GND")
		(2 "B.Cu" signal "BOTTOM")
		(9 "F.Adhes" user "F.Adhesive")
		(11 "B.Adhes" user "B.Adhesive")
		(13 "F.Paste" user "Package Geometry/Pastemask Top")
		(15 "B.Paste" user "Package Geometry/Pastemask Bottom")
		(5 "F.SilkS" user "Ref Des/Silkscreen Top")
		(7 "B.SilkS" user "Ref Des/Silkscreen Bottom")
		(1 "F.Mask" user "Board Geometry/Soldermask Top")
		(3 "B.Mask" user "Board Geometry/Soldermask Bottom")
		(17 "Dwgs.User" user "User.Drawings")
		(19 "Cmts.User" user "User.Comments")
		(21 "Eco1.User" user "User.Eco1")
		(23 "Eco2.User" user "User.Eco2")
		(25 "Edge.Cuts" user "Board Geometry/Outline")
		(27 "Margin" user)
		(31 "F.CrtYd" user "Package Geometry/Place Bound Top")
		(29 "B.CrtYd" user "Package Geometry/Place Bound Bottom")
		(35 "F.Fab" user "Ref Des/Assembly Top")
		(33 "B.Fab" user "Ref Des/Assembly Bottom")
	)
	(footprint ""
		(layer "F.Cu")
		(at 29.636466 -53.42763 90)
		(property "Reference" "CT24"
			(at 1.67513 -6.1976 0)
			(unlocked yes)
			(layer "F.SilkS")
			(effects
				(font
					(size 0.7874 0.5842)
					(thickness 0.1524)
				)
				(justify left)
			)
		)
		(property "Value" ""
			(at 0 0 90)
			(layer "F.Fab")
			(effects
				(font
					(size 1.27 1.27)
				)
			)
		)
		(duplicate_pad_numbers_are_jumpers no)
		(fp_poly
			(pts
				(xy 0.3048 -0.1016) (xy 0.3048 0.9906) (xy -0.3048 0.9906) (xy -0.3048 -0.1016)
			)
			(stroke
				(width 0)
				(type default)
			)
			(fill no)
			(layer "F.CrtYd")
		)
		(fp_line
			(start 0.3048 -0.1016)
			(end -0.3048 -0.1016)
			(stroke
				(width 0.1)
				(type default)
			)
			(layer "F.Fab")
		)
		(fp_line
			(start -0.3048 -0.1016)
			(end -0.3048 0.9906)
			(stroke
				(width 0.1)
				(type default)
			)
			(layer "F.Fab")
		)
		(fp_line
			(start 0.3048 0.9906)
			(end 0.3048 -0.1016)
			(stroke
				(width 0.1)
				(type default)
			)
			(layer "F.Fab")
		)
		(fp_line
			(start -0.3048 0.9906)
			(end 0.3048 0.9906)
			(stroke
				(width 0.1)
				(type default)
			)
			(layer "F.Fab")
		)
		(pad "1" smd rect
			(at 0 0 90)
			(size 0.508 0.508)
			(layers "F.Cu" "F.Mask" "F.Paste")
			(net "VR_PVCCIN_CPU1_AIREF1")
		)
		(pad "2" smd rect
			(at 0 0.889 90)
			(size 0.508 0.508)
			(layers "F.Cu" "F.Mask" "F.Paste")
			(net "GND")
		)
		(zone
			(layer "F.Cu")
			(hatch none 0.5)
			(connect_pads
				(clearance 0)
			)
			(min_thickness 0.25)
			(keepout
				(tracks allowed)
				(vias not_allowed)
				(pads allowed)
				(copperpour not_allowed)
				(footprints allowed)
			)
			(placement
				(enabled no)
				(sheetname "")
			)
			(fill
				(thermal_gap 0.5)
				(thermal_bridge_width 0.5)
				(island_removal_mode 0)
			)
			(polygon
				(pts
					(xy 29.890466 -53.17363) (xy 29.890466 -53.68163) (xy 30.271466 -53.68163) (xy 30.271466 -53.17363)
				)
			)
		)
		(zone
			(layer "F.Cu")
			(hatch none 0.5)
			(connect_pads
				(clearance 0)
			)
			(min_thickness 0.25)
			(keepout
				(tracks not_allowed)
				(vias allowed)
				(pads allowed)
				(copperpour not_allowed)
				(footprints allowed)
			)
			(placement
				(enabled no)
				(sheetname "")
			)
			(fill
				(thermal_gap 0.5)
				(thermal_bridge_width 0.5)
				(island_removal_mode 0)
			)
			(polygon
				(pts
					(xy 30.271466 -53.17363) (xy 30.271466 -53.68163) (xy 29.890466 -53.68163) (xy 29.890466 -53.17363)
				)
			)
		)
	)
	(footprint ""
		(layer "F.Cu")
		(at 323.0245 -118.415816 -90)
		(property "Reference" "C833"
			(at -0.8382 -0.67818 270)
			(unlocked yes)
			(layer "F.SilkS")
			(effects
				(font
					(size 0.4064 0.254)
					(thickness 0.1524)
				)
				(justify left)
			)
		)
		(property "Value" ""
			(at 0 0 270)
			(layer "F.Fab")
			(effects
				(font
					(size 1.27 1.27)
				)
			)
		)
		(duplicate_pad_numbers_are_jumpers no)
		(fp_poly
			(pts
				(xy 0.3048 -0.1016) (xy 0.3048 0.9906) (xy -0.3048 0.9906) (xy -0.3048 -0.1016)
			)
			(stroke
				(width 0)
				(type default)
			)
			(fill no)
			(layer "F.CrtYd")
		)
		(fp_line
			(start -0.3048 0.9906)
			(end 0.3048 0.9906)
			(stroke
				(width 0.1)
				(type default)
			)
			(layer "F.Fab")
		)
		(fp_line
			(start 0.3048 0.9906)
			(end 0.3048 -0.1016)
			(stroke
				(width 0.1)
				(type default)
			)
			(layer "F.Fab")
		)
		(fp_line
			(start -0.3048 -0.1016)
			(end -0.3048 0.9906)
			(stroke
				(width 0.1)
				(type default)
			)
			(layer "F.Fab")
		)
		(fp_line
			(start 0.3048 -0.1016)
			(end -0.3048 -0.1016)
			(stroke
				(width 0.1)
				(type default)
			)
			(layer "F.Fab")
		)
		(pad "1" smd rect
			(at 0 0 270)
			(size 0.508 0.508)
			(layers "F.Cu" "F.Mask" "F.Paste")
			(net "P3E_CPU0_PE1_PCH_TXP<11>")
		)
		(pad "2" smd rect
			(at 0 0.889 270)
			(size 0.508 0.508)
			(layers "F.Cu" "F.Mask" "F.Paste")
			(net "P3E_CPU0_PE1_PCH_CON_TXP<11>")
		)
		(zone
			(layer "F.Cu")
			(hatch none 0.5)
			(connect_pads
				(clearance 0)
			)
			(min_thickness 0.25)
			(keepout
				(tracks not_allowed)
				(vias allowed)
				(pads allowed)
				(copperpour not_allowed)
				(footprints allowed)
			)
			(placement
				(enabled no)
				(sheetname "")
			)
			(fill
				(thermal_gap 0.5)
				(thermal_bridge_width 0.5)
				(island_removal_mode 0)
			)
			(polygon
				(pts
					(xy 322.3895 -118.669816) (xy 322.3895 -118.161816) (xy 322.7705 -118.161816) (xy 322.7705 -118.669816)
				)
			)
		)
		(zone
			(layer "F.Cu")
			(hatch none 0.5)
			(connect_pads
				(clearance 0)
			)
			(min_thickness 0.25)
			(keepout
				(tracks allowed)
				(vias not_allowed)
				(pads allowed)
				(copperpour not_allowed)
				(footprints allowed)
			)
			(placement
				(enabled no)
				(sheetname "")
			)
			(fill
				(thermal_gap 0.5)
				(thermal_bridge_width 0.5)
				(island_removal_mode 0)
			)
			(polygon
				(pts
					(xy 322.7705 -118.669816) (xy 322.7705 -118.161816) (xy 322.3895 -118.161816) (xy 322.3895 -118.669816)
				)
			)
		)
	)
	(footprint ""
		(layer "F.Cu")
		(at 360.622088 -142.03172 -90)
		(property "Reference" "RF18"
			(at -0.8382 -0.67818 270)
			(unlocked yes)
			(layer "F.SilkS")
			(effects
				(font
					(size 0.4064 0.254)
					(thickness 0.1524)
				)
				(justify left)
			)
		)
		(property "Value" ""
			(at 0 0 270)
			(layer "F.Fab")
			(effects
				(font
					(size 1.27 1.27)
				)
			)
		)
		(duplicate_pad_numbers_are_jumpers no)
		(fp_poly
			(pts
				(xy -0.2794 -0.1016) (xy 0.2794 -0.1016) (xy 0.2794 0.9906) (xy -0.2794 0.9906)
			)
			(stroke
				(width 0)
				(type default)
			)
			(fill no)
			(layer "F.CrtYd")
		)
		(fp_line
			(start -0.2794 0.9906)
			(end 0.2794 0.9906)
			(stroke
				(width 0.1)
				(type default)
			)
			(layer "F.Fab")
		)
		(fp_line
			(start 0.2794 0.9906)
			(end 0.2794 -0.1016)
			(stroke
				(width 0.1)
				(type default)
			)
			(layer "F.Fab")
		)
		(fp_line
			(start -0.2794 -0.1016)
			(end -0.2794 0.9906)
			(stroke
				(width 0.1)
				(type default)
			)
			(layer "F.Fab")
		)
		(fp_line
			(start 0.2794 -0.1016)
			(end -0.2794 -0.1016)
			(stroke
				(width 0.1)
				(type default)
			)
			(layer "F.Fab")
		)
		(pad "1" smd rect
			(at 0 0 270)
			(size 0.508 0.508)
			(layers "F.Cu" "F.Mask" "F.Paste")
			(net "VR_PVDDQ_DEF_AIREF2")
		)
		(pad "2" smd rect
			(at 0 0.889 270)
			(size 0.508 0.508)
			(layers "F.Cu" "F.Mask" "F.Paste")
			(net "ISENSE_PVDDQ_DEF_PH2_IMON")
		)
		(zone
			(layer "F.Cu")
			(hatch none 0.5)
			(connect_pads
				(clearance 0)
			)
			(min_thickness 0.25)
			(keepout
				(tracks not_allowed)
				(vias allowed)
				(pads allowed)
				(copperpour not_allowed)
				(footprints allowed)
			)
			(placement
				(enabled no)
				(sheetname "")
			)
			(fill
				(thermal_gap 0.5)
				(thermal_bridge_width 0.5)
				(island_removal_mode 0)
			)
			(polygon
				(pts
					(xy 359.987088 -142.28572) (xy 359.987088 -141.77772) (xy 360.368088 -141.77772) (xy 360.368088 -142.28572)
				)
			)
		)
		(zone
			(layer "F.Cu")
			(hatch none 0.5)
			(connect_pads
				(clearance 0)
			)
			(min_thickness 0.25)
			(keepout
				(tracks allowed)
				(vias not_allowed)
				(pads allowed)
				(copperpour not_allowed)
				(footprints allowed)
			)
			(placement
				(enabled no)
				(sheetname "")
			)
			(fill
				(thermal_gap 0.5)
				(thermal_bridge_width 0.5)
				(island_removal_mode 0)
			)
			(polygon
				(pts
					(xy 360.368088 -142.28572) (xy 360.368088 -141.77772) (xy 359.987088 -141.77772) (xy 359.987088 -142.28572)
				)
			)
		)
	)
)
